# T6G (Grand Teton) — schematic netlist excerpt (pin names and nets, part order shuffled) for the footprints in the layout excerpt that follows; sources: Cadence DE-HDL packaged netlist, KiCad conversion of 04192023_DAF0TMB3IC0_F0TG_MB_C_brd_V02_OCP.brd

J111  CONN112_10137002101LF  CONN112_10137002-101LF IO  pkg HSD_F112D8_P2W1-2_RDH  page 121
  A1  = GPU_PEX_STRAP1
  A2  = GND
  A3  = GPU_BASE_ID0
  A4  = GND
  A5  = GPU_PEX_STRAP0
  A6  = GND
  A7  = GPU_FPGA_RST_R_BUF_N
  A8  = GND
  B1  = GND
  B2  = P5E_CPU1_P0_RX_BUF_DN<9>
  B3  = GND
  B4  = P5E_CPU1_P0_RX_BUF_DN<11>
  B5  = GND
  B6  = P5E_CPU1_P0_RX_BUF_DN<13>
  B7  = GND
  B8  = P5E_CPU1_P0_RX_BUF_DN<15>
  C1  = P5E_CPU1_P0_RX_BUF_DN<8>
  C2  = P5E_CPU1_P0_RX_BUF_DP<9>
  C3  = P5E_CPU1_P0_RX_BUF_DN<10>
  C4  = P5E_CPU1_P0_RX_BUF_DP<11>
  C5  = P5E_CPU1_P0_RX_BUF_DN<12>
  C6  = P5E_CPU1_P0_RX_BUF_DP<13>
  C7  = P5E_CPU1_P0_RX_BUF_DN<14>
  C8  = P5E_CPU1_P0_RX_BUF_DP<15>
  D1  = P5E_CPU1_P0_RX_BUF_DP<8>
  D2  = GND
  D3  = P5E_CPU1_P0_RX_BUF_DP<10>
  D4  = GND
  D5  = P5E_CPU1_P0_RX_BUF_DP<12>
  D6  = GND
  D7  = P5E_CPU1_P0_RX_BUF_DP<14>
  D8  = GND
  E1  = GND
  E2  = P5E_CPU1_P1_RX_BUF_DN<9>
  E3  = GND
  E4  = P5E_CPU1_P1_RX_BUF_DN<11>
  E5  = GND
  E6  = P5E_CPU1_P1_RX_BUF_DN<13>
  E7  = GND
  E8  = P5E_CPU1_P1_RX_BUF_DN<15>
  F1  = P5E_CPU1_P1_RX_BUF_DN<8>
  F2  = P5E_CPU1_P1_RX_BUF_DP<9>
  F3  = P5E_CPU1_P1_RX_BUF_DN<10>
  F4  = P5E_CPU1_P1_RX_BUF_DP<11>
  F5  = P5E_CPU1_P1_RX_BUF_DN<12>
  F6  = P5E_CPU1_P1_RX_BUF_DP<13>
  F7  = P5E_CPU1_P1_RX_BUF_DN<14>
  F8  = P5E_CPU1_P1_RX_BUF_DP<15>
  G1  = P5E_CPU1_P1_RX_BUF_DP<8>
  G2  = GND
  G3  = P5E_CPU1_P1_RX_BUF_DP<10>
  G4  = GND
  G5  = P5E_CPU1_P1_RX_BUF_DP<12>
  G6  = GND
  G7  = P5E_CPU1_P1_RX_BUF_DP<14>
  G8  = GND
  H1  = GND
  H2  = P5E_CPU1_P0_TX_BUF_C_DN<9>
  H3  = GND
  H4  = P5E_CPU1_P0_TX_BUF_C_DN<11>
  H5  = GND
  H6  = P5E_CPU1_P0_TX_BUF_C_DN<13>
  H7  = GND
  H8  = P5E_CPU1_P0_TX_BUF_C_DN<15>
  I1  = P5E_CPU1_P0_TX_BUF_C_DN<8>
  I2  = P5E_CPU1_P0_TX_BUF_C_DP<9>
  I3  = P5E_CPU1_P0_TX_BUF_C_DN<10>
  I4  = P5E_CPU1_P0_TX_BUF_C_DP<11>
  I5  = P5E_CPU1_P0_TX_BUF_C_DN<12>
  I6  = P5E_CPU1_P0_TX_BUF_C_DP<13>
  I7  = P5E_CPU1_P0_TX_BUF_C_DN<14>
  I8  = P5E_CPU1_P0_TX_BUF_C_DP<15>
  J1  = P5E_CPU1_P0_TX_BUF_C_DP<8>
  J2  = GND
  J3  = P5E_CPU1_P0_TX_BUF_C_DP<10>
  J4  = GND
  J5  = P5E_CPU1_P0_TX_BUF_C_DP<12>
  J6  = GND
  J7  = P5E_CPU1_P0_TX_BUF_C_DP<14>
  J8  = GND
  K1  = GND
  K2  = P5E_CPU1_P1_TX_BUF_C_DN<9>
  K3  = GND
  K4  = P5E_CPU1_P1_TX_BUF_C_DN<11>
  K5  = GND
  K6  = P5E_CPU1_P1_TX_BUF_C_DN<13>
  K7  = GND
  K8  = P5E_CPU1_P1_TX_BUF_C_DN<15>
  L1  = P5E_CPU1_P1_TX_BUF_C_DN<8>
  L2  = P5E_CPU1_P1_TX_BUF_C_DP<9>
  L3  = P5E_CPU1_P1_TX_BUF_C_DN<10>
  L4  = P5E_CPU1_P1_TX_BUF_C_DP<11>
  L5  = P5E_CPU1_P1_TX_BUF_C_DN<12>
  L6  = P5E_CPU1_P1_TX_BUF_C_DP<13>
  L7  = P5E_CPU1_P1_TX_BUF_C_DN<14>
  L8  = P5E_CPU1_P1_TX_BUF_C_DP<15>
  M1  = P5E_CPU1_P1_TX_BUF_C_DP<8>
  M2  = GND
  M3  = P5E_CPU1_P1_TX_BUF_C_DP<10>
  M4  = GND
  M5  = P5E_CPU1_P1_TX_BUF_C_DP<12>
  M6  = GND
  M7  = P5E_CPU1_P1_TX_BUF_C_DP<14>
  M8  = GND
  N1  = GND
  N2  = GPU_PRSNT_N
  N3  = GND
  N4  = FM_GPU_PWR_EN_R_BUF
  N5  = GND
  N6  = FM_GPU_PWRGD
  N7  = GND
  N8  = GPU_BASE_ID1

(kicad_pcb
	(version 20260206)
	(generator "pcbnew")
	(generator_version "10.0")
	(general
		(thickness 1.6)
		(legacy_teardrops no)
	)
	(paper "A4")
	(title_block
		(title "04192023_DAF0TMB3IC0_F0TG_MB_C_brd_V02_OCP.brd")
		(comment 1 "Grand Teton / footprint 2176 of 8354 (J111), pads 32-48 of 48")
	)
	(layers
		(0 "F.Cu" signal "TOP")
		(4 "In1.Cu" signal "GND")
		(6 "In2.Cu" signal "IN1")
		(8 "In3.Cu" signal "GND1")
		(10 "In4.Cu" signal "IN2")
		(12 "In5.Cu" signal "GND2")
		(14 "In6.Cu" signal "IN3")
		(16 "In7.Cu" signal "GND3")
		(18 "In8.Cu" signal "VCC")
		(20 "In9.Cu" signal "VCC1")
		(22 "In10.Cu" signal "GND4")
		(24 "In11.Cu" signal "IN4")
		(26 "In12.Cu" signal "GND5")
		(28 "In13.Cu" signal "IN5")
		(30 "In14.Cu" signal "GND6")
		(32 "In15.Cu" signal "IN6")
		(34 "In16.Cu" signal "GND7")
		(2 "B.Cu" signal "BOTTOM")
		(9 "F.Adhes" user "F.Adhesive")
		(11 "B.Adhes" user "B.Adhesive")
		(13 "F.Paste" user "Package Geometry/Pastemask Top")
		(15 "B.Paste" user "Package Geometry/Pastemask Bottom")
		(5 "F.SilkS" user "Ref Des/Silkscreen Top")
		(7 "B.SilkS" user "Ref Des/Silkscreen Bottom")
		(1 "F.Mask" user "Board Geometry/Soldermask Top")
		(3 "B.Mask" user "Board Geometry/Soldermask Bottom")
		(17 "Dwgs.User" user "User.Drawings")
		(19 "Cmts.User" user "User.Comments")
		(21 "Eco1.User" user "User.Eco1")
		(23 "Eco2.User" user "User.Eco2")
		(25 "Edge.Cuts" user "Board Geometry/Outline")
		(27 "Margin" user)
		(31 "F.CrtYd" user "Package Geometry/Place Bound Top")
		(29 "B.CrtYd" user "Package Geometry/Place Bound Bottom")
		(35 "F.Fab" user "Ref Des/Assembly Top")
		(33 "B.Fab" user "Ref Des/Assembly Bottom")
	)
	(footprint ""
		(layer "F.Cu")
		(at 75.65009 -440.489848)
		(property "Reference" "J111"
			(at 14.3637 23.187152 0)
			(unlocked yes)
			(layer "F.SilkS")
			(effects
				(font
					(size 0.7874 0.5842)
					(thickness 0.1524)
				)
				(justify left)
			)
		)
		(property "Value" ""
			(at 0 0 0)
			(layer "F.Fab")
			(effects
				(font
					(size 1.27 1.27)
				)
			)
		)
		(duplicate_pad_numbers_are_jumpers no)
		(pad "J8" thru_hole circle
			(at 13.999972 10.999978 180)
			(size 0.906272 0.906272)
			(drill 0.499872)
			(layers "*.Cu" "*.Mask")
			(remove_unused_layers no)
			(net "GND")
			(clearance 0.0508)
			(thermal_gap 0.0508)
		)
		(pad "K1" thru_hole circle
			(at 0 11.999976 180)
			(size 0.906272 0.906272)
			(drill 0.499872)
			(layers "*.Cu" "*.Mask")
			(remove_unused_layers no)
			(net "GND")
			(clearance 0.0508)
			(thermal_gap 0.0508)
		)
		(pad "K3" thru_hole circle
			(at 3.999992 11.999976 180)
			(size 0.906272 0.906272)
			(drill 0.499872)
			(layers "*.Cu" "*.Mask")
			(remove_unused_layers no)
			(net "GND")
			(clearance 0.0508)
			(thermal_gap 0.0508)
		)
		(pad "K5" thru_hole circle
			(at 7.999984 11.999976 180)
			(size 0.906272 0.906272)
			(drill 0.499872)
			(layers "*.Cu" "*.Mask")
			(remove_unused_layers no)
			(net "GND")
			(clearance 0.0508)
			(thermal_gap 0.0508)
		)
		(pad "K7" thru_hole circle
			(at 11.999976 11.999976 180)
			(size 0.906272 0.906272)
			(drill 0.499872)
			(layers "*.Cu" "*.Mask")
			(remove_unused_layers no)
			(net "GND")
			(clearance 0.0508)
			(thermal_gap 0.0508)
		)
		(pad "M2" thru_hole circle
			(at 1.999996 14.59992 180)
			(size 0.906272 0.906272)
			(drill 0.499872)
			(layers "*.Cu" "*.Mask")
			(remove_unused_layers no)
			(net "GND")
			(clearance 0.0508)
			(thermal_gap 0.0508)
		)
		(pad "M4" thru_hole circle
			(at 5.999988 14.59992 180)
			(size 0.906272 0.906272)
			(drill 0.499872)
			(layers "*.Cu" "*.Mask")
			(remove_unused_layers no)
			(net "GND")
			(clearance 0.0508)
			(thermal_gap 0.0508)
		)
		(pad "M6" thru_hole circle
			(at 9.99998 14.59992 180)
			(size 0.906272 0.906272)
			(drill 0.499872)
			(layers "*.Cu" "*.Mask")
			(remove_unused_layers no)
			(net "GND")
			(clearance 0.0508)
			(thermal_gap 0.0508)
		)
		(pad "M8" thru_hole circle
			(at 13.999972 14.59992 180)
			(size 0.906272 0.906272)
			(drill 0.499872)
			(layers "*.Cu" "*.Mask")
			(remove_unused_layers no)
			(net "GND")
			(clearance 0.0508)
			(thermal_gap 0.0508)
		)
		(pad "N1" thru_hole circle
			(at 0 15.599918 180)
			(size 0.906272 0.906272)
			(drill 0.499872)
			(layers "*.Cu" "*.Mask")
			(remove_unused_layers no)
			(net "GND")
			(clearance 0.0508)
			(thermal_gap 0.0508)
		)
		(pad "N2" thru_hole circle
			(at 1.999996 15.80007 180)
			(size 0.766318 0.766318)
			(drill 0.359918)
			(layers "*.Cu" "*.Mask")
			(remove_unused_layers no)
			(net "GPU_PRSNT_N")
			(clearance 0.0508)
			(thermal_gap 0.0508)
		)
		(pad "N3" thru_hole circle
			(at 3.999992 15.599918 180)
			(size 0.906272 0.906272)
			(drill 0.499872)
			(layers "*.Cu" "*.Mask")
			(remove_unused_layers no)
			(net "GND")
			(clearance 0.0508)
			(thermal_gap 0.0508)
		)
		(pad "N4" thru_hole circle
			(at 5.999988 15.80007 180)
			(size 0.766318 0.766318)
			(drill 0.359918)
			(layers "*.Cu" "*.Mask")
			(remove_unused_layers no)
			(net "FM_GPU_PWR_EN_R_BUF")
			(clearance 0.0508)
			(thermal_gap 0.0508)
		)
		(pad "N5" thru_hole circle
			(at 7.999984 15.599918 180)
			(size 0.906272 0.906272)
			(drill 0.499872)
			(layers "*.Cu" "*.Mask")
			(remove_unused_layers no)
			(net "GND")
			(clearance 0.0508)
			(thermal_gap 0.0508)
		)
		(pad "N6" thru_hole circle
			(at 9.99998 15.80007 180)
			(size 0.766318 0.766318)
			(drill 0.359918)
			(layers "*.Cu" "*.Mask")
			(remove_unused_layers no)
			(net "FM_GPU_PWRGD")
			(clearance 0.0508)
			(thermal_gap 0.0508)
		)
		(pad "N7" thru_hole circle
			(at 11.999976 15.599918 180)
			(size 0.906272 0.906272)
			(drill 0.499872)
			(layers "*.Cu" "*.Mask")
			(remove_unused_layers no)
			(net "GND")
			(clearance 0.0508)
			(thermal_gap 0.0508)
		)
		(pad "N8" thru_hole circle
			(at 13.999972 15.80007 180)
			(size 0.766318 0.766318)
			(drill 0.359918)
			(layers "*.Cu" "*.Mask")
			(remove_unused_layers no)
			(net "GPU_BASE_ID1")
			(clearance 0.0508)
			(thermal_gap 0.0508)
		)
	)
)
